# S9S_MB_2U (Grand Teton) — schematic netlist excerpt (pin names and nets, part order shuffled) for the footprints in the layout excerpt that follows; sources: Cadence DE-HDL packaged netlist, KiCad conversion of 03242023_DA0F0TMBIJ0_F0T_Motherboard_J_brd_V01_OCP.brd

PC2158  Q_CAP  2.2UF 16V 20% X7R  pkg C0603  page 157 : A = P12V_OCP_AVIN_PD_1 ; B = GND
C221  Q_CAP  10UF 6.3V 20% X6S  pkg C0402  page 77 : A = PVCCIN_CPU1 ; B = GND

(kicad_pcb
	(version 20260206)
	(generator "pcbnew")
	(generator_version "10.0")
	(general
		(thickness 1.6)
		(legacy_teardrops no)
	)
	(paper "A4")
	(title_block
		(title "03242023_DA0F0TMBIJ0_F0T_Motherboard_J_brd_V01_OCP.brd")
		(comment 1 "Grand Teton / footprints 1963-1964 of 6105")
	)
	(layers
		(0 "F.Cu" signal "TOP")
		(4 "In1.Cu" signal "GND")
		(6 "In2.Cu" signal "IN1")
		(8 "In3.Cu" signal "GND1")
		(10 "In4.Cu" signal "IN2")
		(12 "In5.Cu" signal "GND2")
		(14 "In6.Cu" signal "IN3")
		(16 "In7.Cu" signal "GND3")
		(18 "In8.Cu" signal "VCC")
		(20 "In9.Cu" signal "VCC1")
		(22 "In10.Cu" signal "GND4")
		(24 "In11.Cu" signal "IN4")
		(26 "In12.Cu" signal "GND5")
		(28 "In13.Cu" signal "IN5")
		(30 "In14.Cu" signal "GND6")
		(32 "In15.Cu" signal "IN6")
		(34 "In16.Cu" signal "GND7")
		(2 "B.Cu" signal "BOTTOM")
		(9 "F.Adhes" user "F.Adhesive")
		(11 "B.Adhes" user "B.Adhesive")
		(13 "F.Paste" user "Package Geometry/Pastemask Top")
		(15 "B.Paste" user "Package Geometry/Pastemask Bottom")
		(5 "F.SilkS" user "Ref Des/Silkscreen Top")
		(7 "B.SilkS" user "Ref Des/Silkscreen Bottom")
		(1 "F.Mask" user "Board Geometry/Soldermask Top")
		(3 "B.Mask" user "Board Geometry/Soldermask Bottom")
		(17 "Dwgs.User" user "User.Drawings")
		(19 "Cmts.User" user "User.Comments")
		(21 "Eco1.User" user "User.Eco1")
		(23 "Eco2.User" user "User.Eco2")
		(25 "Edge.Cuts" user "Board Geometry/Outline")
		(27 "Margin" user)
		(31 "F.CrtYd" user "Package Geometry/Place Bound Top")
		(29 "B.CrtYd" user "Package Geometry/Place Bound Bottom")
		(35 "F.Fab" user "Ref Des/Assembly Top")
		(33 "B.Fab" user "Ref Des/Assembly Bottom")
	)
	(footprint ""
		(layer "F.Cu")
		(at 107.287314 -258.72694 90)
		(property "Reference" "C221"
			(at 0 0 90)
			(layer "F.SilkS")
			(hide yes)
			(effects
				(font
					(size 1.27 1.27)
				)
			)
		)
		(property "Value" ""
			(at 0 0 90)
			(layer "F.Fab")
			(effects
				(font
					(size 1.27 1.27)
				)
			)
		)
		(duplicate_pad_numbers_are_jumpers no)
		(fp_line
			(start 0.7874 -0.4064)
			(end 0.7874 0.4064)
			(stroke
				(width 0.1524)
				(type default)
			)
			(layer "F.SilkS")
		)
		(fp_line
			(start -0.7874 -0.4064)
			(end 0.7874 -0.4064)
			(stroke
				(width 0.1524)
				(type default)
			)
			(layer "F.SilkS")
		)
		(fp_line
			(start 0.7874 0.4064)
			(end -0.7874 0.4064)
			(stroke
				(width 0.1524)
				(type default)
			)
			(layer "F.SilkS")
		)
		(fp_line
			(start -0.7874 0.4064)
			(end -0.7874 -0.4064)
			(stroke
				(width 0.1524)
				(type default)
			)
			(layer "F.SilkS")
		)
		(fp_line
			(start -0.12065 -0.305054)
			(end -0.12065 -0.2794)
			(stroke
				(width 0.1)
				(type default)
			)
			(layer "F.Fab")
		)
		(fp_line
			(start -0.67945 -0.305054)
			(end -0.12065 -0.305054)
			(stroke
				(width 0.1)
				(type default)
			)
			(layer "F.Fab")
		)
		(fp_line
			(start 0.67945 -0.3048)
			(end 0.67945 0.3048)
			(stroke
				(width 0.1)
				(type default)
			)
			(layer "F.Fab")
		)
		(fp_line
			(start 0.12065 -0.3048)
			(end 0.67945 -0.3048)
			(stroke
				(width 0.1)
				(type default)
			)
			(layer "F.Fab")
		)
		(fp_line
			(start 0.12065 -0.2794)
			(end 0.12065 -0.3048)
			(stroke
				(width 0.1)
				(type default)
			)
			(layer "F.Fab")
		)
		(fp_line
			(start -0.12065 -0.2794)
			(end 0.12065 -0.2794)
			(stroke
				(width 0.1)
				(type default)
			)
			(layer "F.Fab")
		)
		(fp_line
			(start 0.120396 0.2794)
			(end -0.12065 0.2794)
			(stroke
				(width 0.1)
				(type default)
			)
			(layer "F.Fab")
		)
		(fp_line
			(start -0.12065 0.2794)
			(end -0.12065 0.3048)
			(stroke
				(width 0.1)
				(type default)
			)
			(layer "F.Fab")
		)
		(fp_line
			(start 0.67945 0.3048)
			(end 0.120396 0.3048)
			(stroke
				(width 0.1)
				(type default)
			)
			(layer "F.Fab")
		)
		(fp_line
			(start 0.120396 0.3048)
			(end 0.120396 0.2794)
			(stroke
				(width 0.1)
				(type default)
			)
			(layer "F.Fab")
		)
		(fp_line
			(start -0.12065 0.3048)
			(end -0.67945 0.3048)
			(stroke
				(width 0.1)
				(type default)
			)
			(layer "F.Fab")
		)
		(fp_line
			(start -0.67945 0.3048)
			(end -0.67945 -0.305054)
			(stroke
				(width 0.1)
				(type default)
			)
			(layer "F.Fab")
		)
		(pad "1" smd circle
			(at -0.40005 0 90)
			(size 0 0)
			(layers "F.Cu" "F.Mask" "F.Paste")
			(net "PVCCIN_CPU1")
		)
		(pad "2" smd circle
			(at 0.40005 0 90)
			(size 0 0)
			(layers "F.Cu" "F.Mask" "F.Paste")
			(net "GND")
		)
	)
	(footprint ""
		(layer "F.Cu")
		(at 439.295032 -25.084278 180)
		(property "Reference" "PC2158"
			(at 0 0 180)
			(layer "F.SilkS")
			(hide yes)
			(effects
				(font
					(size 1.27 1.27)
				)
			)
		)
		(property "Value" ""
			(at 0 0 180)
			(layer "F.Fab")
			(effects
				(font
					(size 1.27 1.27)
				)
			)
		)
		(duplicate_pad_numbers_are_jumpers no)
		(fp_line
			(start 1.2954 0.5842)
			(end -1.2954 0.5842)
			(stroke
				(width 0.1524)
				(type default)
			)
			(layer "F.SilkS")
		)
		(fp_line
			(start 1.2954 -0.5842)
			(end 1.2954 0.5842)
			(stroke
				(width 0.1524)
				(type default)
			)
			(layer "F.SilkS")
		)
		(fp_line
			(start 0 -0.5842)
			(end 0 0.5842)
			(stroke
				(width 0.1524)
				(type default)
			)
			(layer "F.SilkS")
		)
		(fp_line
			(start -1.2954 0.5842)
			(end -1.2954 -0.5842)
			(stroke
				(width 0.1524)
				(type default)
			)
			(layer "F.SilkS")
		)
		(fp_line
			(start -1.2954 -0.5842)
			(end 1.2954 -0.5842)
			(stroke
				(width 0.1524)
				(type default)
			)
			(layer "F.SilkS")
		)
		(fp_line
			(start 1.1938 0.4064)
			(end 0.8636 0.4064)
			(stroke
				(width 0.1)
				(type default)
			)
			(layer "F.Fab")
		)
		(fp_line
			(start 1.1938 -0.4064)
			(end 1.1938 0.4064)
			(stroke
				(width 0.1)
				(type default)
			)
			(layer "F.Fab")
		)
		(fp_line
			(start 0.8636 0.4572)
			(end -0.8636 0.4572)
			(stroke
				(width 0.1)
				(type default)
			)
			(layer "F.Fab")
		)
		(fp_line
			(start 0.8636 0.4064)
			(end 0.8636 0.4572)
			(stroke
				(width 0.1)
				(type default)
			)
			(layer "F.Fab")
		)
		(fp_line
			(start 0.8636 -0.4064)
			(end 1.1938 -0.4064)
			(stroke
				(width 0.1)
				(type default)
			)
			(layer "F.Fab")
		)
		(fp_line
			(start 0.8636 -0.4572)
			(end 0.8636 -0.4064)
			(stroke
				(width 0.1)
				(type default)
			)
			(layer "F.Fab")
		)
		(fp_line
			(start -0.8636 0.4572)
			(end -0.8636 0.4064)
			(stroke
				(width 0.1)
				(type default)
			)
			(layer "F.Fab")
		)
		(fp_line
			(start -0.8636 0.4064)
			(end -1.1938 0.4064)
			(stroke
				(width 0.1)
				(type default)
			)
			(layer "F.Fab")
		)
		(fp_line
			(start -0.8636 -0.4064)
			(end -0.8636 -0.4572)
			(stroke
				(width 0.1)
				(type default)
			)
			(layer "F.Fab")
		)
		(fp_line
			(start -0.8636 -0.4572)
			(end 0.8636 -0.4572)
			(stroke
				(width 0.1)
				(type default)
			)
			(layer "F.Fab")
		)
		(fp_line
			(start -1.1938 0.4064)
			(end -1.1938 -0.4064)
			(stroke
				(width 0.1)
				(type default)
			)
			(layer "F.Fab")
		)
		(fp_line
			(start -1.1938 -0.4064)
			(end -0.8636 -0.4064)
			(stroke
				(width 0.1)
				(type default)
			)
			(layer "F.Fab")
		)
		(pad "1" smd rect
			(at -0.7366 0 90)
			(size 0.7112 0.8128)
			(layers "F.Cu" "F.Mask" "F.Paste")
			(net "P12V_OCP_AVIN_PD_1")
		)
		(pad "2" smd rect
			(at 0.7366 0 90)
			(size 0.7112 0.8128)
			(layers "F.Cu" "F.Mask" "F.Paste")
			(net "GND")
		)
	)
)
